(kicad_pcb
	(version 20260206)
	(generator "pcbnew")
	(generator_version "10.0")
	(general
		(thickness 1.6)
		(legacy_teardrops no)
	)
	(paper "A4")
	(title_block
		(title "Bryce Canyon_IOM_IOC_16318-2_OCP.brd")
		(comment 1 "Bryce Canyon / footprints 414-422 of 1605")
	)
	(layers
		(0 "F.Cu" signal "TOP")
		(4 "In1.Cu" signal "L2GND")
		(6 "In2.Cu" signal "L3")
		(8 "In3.Cu" signal "L4VCC")
		(10 "In4.Cu" signal "L5VCC")
		(12 "In5.Cu" signal "L6")
		(14 "In6.Cu" signal "L7GND")
		(2 "B.Cu" signal "BOTTOM")
		(9 "F.Adhes" user "F.Adhesive")
		(11 "B.Adhes" user "B.Adhesive")
		(13 "F.Paste" user "Package Geometry/Pastemask Top")
		(15 "B.Paste" user "Package Geometry/Pastemask Bottom")
		(5 "F.SilkS" user "Ref Des/Silkscreen Top")
		(7 "B.SilkS" user "Ref Des/Silkscreen Bottom")
		(1 "F.Mask" user "Board Geometry/Soldermask Top")
		(3 "B.Mask" user "Board Geometry/Soldermask Bottom")
		(17 "Dwgs.User" user "User.Drawings")
		(19 "Cmts.User" user "User.Comments")
		(21 "Eco1.User" user "User.Eco1")
		(23 "Eco2.User" user "User.Eco2")
		(25 "Edge.Cuts" user "Board Geometry/Outline")
		(27 "Margin" user)
		(31 "F.CrtYd" user "Package Geometry/Place Bound Top")
		(29 "B.CrtYd" user "Package Geometry/Place Bound Bottom")
		(35 "F.Fab" user "Ref Des/Assembly Top")
		(33 "B.Fab" user "Ref Des/Assembly Bottom")
	)
	(footprint ""
		(layer "F.Cu")
		(at 162.323018 -91.513914)
		(property "Reference" "R689"
			(at 0 0 0)
			(layer "F.SilkS")
			(hide yes)
			(effects
				(font
					(size 1.27 1.27)
				)
			)
		)
		(property "Value" "2K2R2F-GP"
			(at 0.064008 -3.993896 0)
			(unlocked yes)
			(layer "F.Fab")
			(hide yes)
			(effects
				(font
					(size 1.016 1.016)
					(thickness 0.1524)
				)
			)
		)
		(property "Device Type" "R402H16"
			(at 0.064008 -5.517896 0)
			(unlocked yes)
			(layer "F.Fab")
			(hide yes)
			(effects
				(font
					(size 1.016 1.016)
					(thickness 0.1524)
				)
			)
		)
		(duplicate_pad_numbers_are_jumpers no)
		(fp_line
			(start -0.508 -0.9398)
			(end -0.508 0.9398)
			(stroke
				(width 0.1524)
				(type default)
			)
			(layer "F.SilkS")
		)
		(fp_line
			(start 0.508 -0.9398)
			(end -0.508 -0.9398)
			(stroke
				(width 0.1524)
				(type default)
			)
			(layer "F.SilkS")
		)
		(fp_rect
			(start -0.508 0.9398)
			(end 0.508 -0.9398)
			(stroke
				(width 0)
				(type default)
			)
			(fill no)
			(layer "F.CrtYd")
		)
		(fp_rect
			(start -0.508 0.9398)
			(end 0.508 -0.9398)
			(stroke
				(width 0)
				(type default)
			)
			(fill no)
			(layer "F.Fab")
		)
		(pad "1" smd custom
			(at 0 -0.4445)
			(size 0.1397 0.1397)
			(layers "F.Cu" "F.Mask" "F.Paste")
			(net "I2C_IOC_SDA")
			(options
				(clearance outline)
				(anchor circle)
			)
			(primitives
				(gr_poly
					(pts
						(arc
							(start -0.1778 -0.2794)
							(mid -0.249642 -0.249642)
							(end -0.2794 -0.1778)
						)
						(arc
							(start -0.2794 0.1778)
							(mid -0.249642 0.249642)
							(end -0.1778 0.2794)
						)
						(arc
							(start 0.1778 0.2794)
							(mid 0.249642 0.249642)
							(end 0.2794 0.1778)
						)
						(arc
							(start 0.2794 -0.1778)
							(mid 0.249642 -0.249642)
							(end 0.1778 -0.2794)
						)
					)
					(width 0)
					(fill yes)
				)
			)
		)
		(pad "2" smd custom
			(at 0 0.4445)
			(size 0.1397 0.1397)
			(layers "F.Cu" "F.Mask" "F.Paste")
			(net "P3V3_STBY")
			(options
				(clearance outline)
				(anchor circle)
			)
			(primitives
				(gr_poly
					(pts
						(arc
							(start -0.1778 -0.2794)
							(mid -0.249642 -0.249642)
							(end -0.2794 -0.1778)
						)
						(arc
							(start -0.2794 0.1778)
							(mid -0.249642 0.249642)
							(end -0.1778 0.2794)
						)
						(arc
							(start 0.1778 0.2794)
							(mid 0.249642 0.249642)
							(end 0.2794 0.1778)
						)
						(arc
							(start 0.2794 -0.1778)
							(mid 0.249642 -0.249642)
							(end 0.1778 -0.2794)
						)
					)
					(width 0)
					(fill yes)
				)
			)
		)
	)
	(footprint ""
		(layer "F.Cu")
		(at 67.7672 -170.0022 180)
		(property "Reference" "R79"
			(at 0 0 180)
			(layer "F.SilkS")
			(hide yes)
			(effects
				(font
					(size 1.27 1.27)
				)
			)
		)
		(property "Value" "470KR2F-GP"
			(at 0.064008 -3.993896 180)
			(unlocked yes)
			(layer "F.Fab")
			(hide yes)
			(effects
				(font
					(size 1.016 1.016)
					(thickness 0.1524)
				)
			)
		)
		(property "Device Type" "R402H16"
			(at 0.064008 -5.517896 180)
			(unlocked yes)
			(layer "F.Fab")
			(hide yes)
			(effects
				(font
					(size 1.016 1.016)
					(thickness 0.1524)
				)
			)
		)
		(duplicate_pad_numbers_are_jumpers no)
		(fp_line
			(start 0.508 -0.9398)
			(end -0.508 -0.9398)
			(stroke
				(width 0.1524)
				(type default)
			)
			(layer "F.SilkS")
		)
		(fp_line
			(start -0.508 -0.9398)
			(end -0.508 0.9398)
			(stroke
				(width 0.1524)
				(type default)
			)
			(layer "F.SilkS")
		)
		(fp_rect
			(start -0.508 0.9398)
			(end 0.508 -0.9398)
			(stroke
				(width 0)
				(type default)
			)
			(fill no)
			(layer "F.CrtYd")
		)
		(fp_rect
			(start -0.508 0.9398)
			(end 0.508 -0.9398)
			(stroke
				(width 0)
				(type default)
			)
			(fill no)
			(layer "F.Fab")
		)
		(pad "1" smd custom
			(at 0 -0.4445 180)
			(size 0.1397 0.1397)
			(layers "F.Cu" "F.Mask" "F.Paste")
			(net "BMC_SELF_HW_RST_D")
			(options
				(clearance outline)
				(anchor circle)
			)
			(primitives
				(gr_poly
					(pts
						(arc
							(start -0.1778 -0.2794)
							(mid -0.249642 -0.249642)
							(end -0.2794 -0.1778)
						)
						(arc
							(start -0.2794 0.1778)
							(mid -0.249642 0.249642)
							(end -0.1778 0.2794)
						)
						(arc
							(start 0.1778 0.2794)
							(mid 0.249642 0.249642)
							(end 0.2794 0.1778)
						)
						(arc
							(start 0.2794 -0.1778)
							(mid 0.249642 -0.249642)
							(end 0.1778 -0.2794)
						)
					)
					(width 0)
					(fill yes)
				)
			)
		)
		(pad "2" smd custom
			(at 0 0.4445 180)
			(size 0.1397 0.1397)
			(layers "F.Cu" "F.Mask" "F.Paste")
			(net "GND")
			(options
				(clearance outline)
				(anchor circle)
			)
			(primitives
				(gr_poly
					(pts
						(arc
							(start -0.1778 -0.2794)
							(mid -0.249642 -0.249642)
							(end -0.2794 -0.1778)
						)
						(arc
							(start -0.2794 0.1778)
							(mid -0.249642 0.249642)
							(end -0.1778 0.2794)
						)
						(arc
							(start 0.1778 0.2794)
							(mid 0.249642 0.249642)
							(end 0.2794 0.1778)
						)
						(arc
							(start 0.2794 -0.1778)
							(mid 0.249642 -0.249642)
							(end 0.1778 -0.2794)
						)
					)
					(width 0)
					(fill yes)
				)
			)
		)
	)
	(footprint ""
		(layer "F.Cu")
		(at 66.1924 -170.1292 -90)
		(property "Reference" "C35"
			(at 0 0 270)
			(layer "F.SilkS")
			(hide yes)
			(effects
				(font
					(size 1.27 1.27)
				)
			)
		)
		(property "Value" "SC1U16V2KX-7-GP"
			(at 1.7526 -1.6002 270)
			(unlocked yes)
			(layer "F.Fab")
			(hide yes)
			(effects
				(font
					(size 1.016 1.016)
					(thickness 0.1524)
				)
			)
		)
		(property "Device Type" "C402-TO0D2H24"
			(at 1.7526 -3.1242 270)
			(unlocked yes)
			(layer "F.Fab")
			(hide yes)
			(effects
				(font
					(size 1.016 1.016)
					(thickness 0.1524)
				)
			)
		)
		(duplicate_pad_numbers_are_jumpers no)
		(fp_rect
			(start -0.4826 0.889)
			(end 0.4826 -0.889)
			(stroke
				(width 0)
				(type default)
			)
			(fill no)
			(layer "F.CrtYd")
		)
		(fp_rect
			(start -0.4826 0.889)
			(end 0.4826 -0.889)
			(stroke
				(width 0)
				(type default)
			)
			(fill no)
			(layer "F.Fab")
		)
		(pad "1" smd custom
			(at 0 -0.4572 270)
			(size 0.1524 0.1524)
			(layers "F.Cu" "F.Mask" "F.Paste")
			(net "BMC_SELF_HW_RST_D")
			(options
				(clearance outline)
				(anchor circle)
			)
			(primitives
				(gr_poly
					(pts
						(arc
							(start -0.254 0.3048)
							(mid -0.325842 0.275042)
							(end -0.3556 0.2032)
						)
						(arc
							(start -0.3556 -0.2032)
							(mid -0.325842 -0.275042)
							(end -0.254 -0.3048)
						)
						(arc
							(start 0.254 -0.3048)
							(mid 0.325842 -0.275042)
							(end 0.3556 -0.2032)
						)
						(arc
							(start 0.3556 0.2032)
							(mid 0.325842 0.275042)
							(end 0.254 0.3048)
						)
					)
					(width 0)
					(fill yes)
				)
			)
		)
		(pad "2" smd custom
			(at 0 0.4572 270)
			(size 0.1524 0.1524)
			(layers "F.Cu" "F.Mask" "F.Paste")
			(net "Q4_G")
			(options
				(clearance outline)
				(anchor circle)
			)
			(primitives
				(gr_poly
					(pts
						(arc
							(start -0.254 0.3048)
							(mid -0.325842 0.275042)
							(end -0.3556 0.2032)
						)
						(arc
							(start -0.3556 -0.2032)
							(mid -0.325842 -0.275042)
							(end -0.254 -0.3048)
						)
						(arc
							(start 0.254 -0.3048)
							(mid 0.325842 -0.275042)
							(end 0.3556 -0.2032)
						)
						(arc
							(start 0.3556 0.2032)
							(mid 0.325842 0.275042)
							(end 0.254 0.3048)
						)
					)
					(width 0)
					(fill yes)
				)
			)
		)
	)
	(footprint ""
		(layer "F.Cu")
		(at 77.81798 -186.683396 180)
		(property "Reference" "C200"
			(at 0 0 180)
			(layer "F.SilkS")
			(hide yes)
			(effects
				(font
					(size 1.27 1.27)
				)
			)
		)
		(property "Value" "SC10U6D3V5KX-4GP"
			(at -0.0762 -6.1214 180)
			(unlocked yes)
			(layer "F.Fab")
			(hide yes)
			(effects
				(font
					(size 1.016 1.016)
					(thickness 0.1524)
				)
			)
		)
		(property "Device Type" "C805H58"
			(at -0.0762 -8.1534 180)
			(unlocked yes)
			(layer "F.Fab")
			(hide yes)
			(effects
				(font
					(size 1.016 1.016)
					(thickness 0.1524)
				)
			)
		)
		(duplicate_pad_numbers_are_jumpers no)
		(fp_line
			(start 0.635 0)
			(end -0.635 0)
			(stroke
				(width 0.508)
				(type default)
			)
			(layer "F.SilkS")
		)
		(fp_rect
			(start -0.9652 1.778)
			(end 0.9652 -1.778)
			(stroke
				(width 0)
				(type default)
			)
			(fill no)
			(layer "F.CrtYd")
		)
		(fp_poly
			(pts
				(xy -0.9652 -1.778) (xy 0.9652 -1.778) (xy 0.9652 1.778) (xy -0.9652 1.778)
			)
			(stroke
				(width 0)
				(type default)
			)
			(fill no)
			(layer "F.Fab")
		)
		(pad "1" smd rect
			(at 0 -0.9652 180)
			(size 1.397 1.143)
			(layers "F.Cu" "F.Mask" "F.Paste")
			(net "P3V3_STBY")
		)
		(pad "2" smd rect
			(at 0 0.9652 180)
			(size 1.397 1.143)
			(layers "F.Cu" "F.Mask" "F.Paste")
			(net "GND")
		)
	)
	(footprint ""
		(layer "F.Cu")
		(at 155.956 -86.1314)
		(property "Reference" "C483"
			(at 0 0 0)
			(layer "F.SilkS")
			(hide yes)
			(effects
				(font
					(size 1.27 1.27)
				)
			)
		)
		(property "Value" "SCD1U16V2KX-3GP"
			(at 1.1811 -2.7051 0)
			(unlocked yes)
			(layer "F.Fab")
			(hide yes)
			(effects
				(font
					(size 1.016 1.016)
					(thickness 0.1524)
				)
			)
		)
		(property "Device Type" "C402H22"
			(at 1.1811 -4.2291 0)
			(unlocked yes)
			(layer "F.Fab")
			(hide yes)
			(effects
				(font
					(size 1.016 1.016)
					(thickness 0.1524)
				)
			)
		)
		(duplicate_pad_numbers_are_jumpers no)
		(fp_rect
			(start -0.4318 0.9525)
			(end 0.4318 -0.9525)
			(stroke
				(width 0)
				(type default)
			)
			(fill no)
			(layer "F.CrtYd")
		)
		(fp_rect
			(start -0.4318 0.9525)
			(end 0.4318 -0.9525)
			(stroke
				(width 0)
				(type default)
			)
			(fill no)
			(layer "F.Fab")
		)
		(pad "1" smd custom
			(at 0 -0.4445)
			(size 0.1524 0.1524)
			(layers "F.Cu" "F.Mask" "F.Paste")
			(net "P1V8")
			(options
				(clearance outline)
				(anchor circle)
			)
			(primitives
				(gr_poly
					(pts
						(arc
							(start 0.3048 -0.2032)
							(mid 0.275042 -0.275042)
							(end 0.2032 -0.3048)
						)
						(arc
							(start -0.2032 -0.3048)
							(mid -0.275042 -0.275042)
							(end -0.3048 -0.2032)
						)
						(arc
							(start -0.3048 0.2032)
							(mid -0.275042 0.275042)
							(end -0.2032 0.3048)
						)
						(arc
							(start 0.2032 0.3048)
							(mid 0.275042 0.275042)
							(end 0.3048 0.2032)
						)
					)
					(width 0)
					(fill yes)
				)
			)
		)
		(pad "2" smd custom
			(at 0 0.4445)
			(size 0.1524 0.1524)
			(layers "F.Cu" "F.Mask" "F.Paste")
			(net "GND")
			(options
				(clearance outline)
				(anchor circle)
			)
			(primitives
				(gr_poly
					(pts
						(arc
							(start 0.3048 -0.2032)
							(mid 0.275042 -0.275042)
							(end 0.2032 -0.3048)
						)
						(arc
							(start -0.2032 -0.3048)
							(mid -0.275042 -0.275042)
							(end -0.3048 -0.2032)
						)
						(arc
							(start -0.3048 0.2032)
							(mid -0.275042 0.275042)
							(end -0.2032 0.3048)
						)
						(arc
							(start 0.2032 0.3048)
							(mid 0.275042 0.275042)
							(end 0.3048 0.2032)
						)
					)
					(width 0)
					(fill yes)
				)
			)
		)
	)
	(footprint ""
		(layer "F.Cu")
		(at 181.37886 -82.94116)
		(property "Reference" "R644"
			(at 0 0 0)
			(layer "F.SilkS")
			(hide yes)
			(effects
				(font
					(size 1.27 1.27)
				)
			)
		)
		(property "Value" "4K7R2F-GP"
			(at 0.064008 -3.993896 0)
			(unlocked yes)
			(layer "F.Fab")
			(hide yes)
			(effects
				(font
					(size 1.016 1.016)
					(thickness 0.1524)
				)
			)
		)
		(property "Device Type" "R402H16"
			(at 0.064008 -5.517896 0)
			(unlocked yes)
			(layer "F.Fab")
			(hide yes)
			(effects
				(font
					(size 1.016 1.016)
					(thickness 0.1524)
				)
			)
		)
		(duplicate_pad_numbers_are_jumpers no)
		(fp_line
			(start -0.508 -0.9398)
			(end -0.508 0.9398)
			(stroke
				(width 0.1524)
				(type default)
			)
			(layer "F.SilkS")
		)
		(fp_line
			(start 0.508 -0.9398)
			(end -0.508 -0.9398)
			(stroke
				(width 0.1524)
				(type default)
			)
			(layer "F.SilkS")
		)
		(fp_rect
			(start -0.508 0.9398)
			(end 0.508 -0.9398)
			(stroke
				(width 0)
				(type default)
			)
			(fill no)
			(layer "F.CrtYd")
		)
		(fp_rect
			(start -0.508 0.9398)
			(end 0.508 -0.9398)
			(stroke
				(width 0)
				(type default)
			)
			(fill no)
			(layer "F.Fab")
		)
		(pad "1" smd custom
			(at 0 -0.4445)
			(size 0.1397 0.1397)
			(layers "F.Cu" "F.Mask" "F.Paste")
			(net "P1V8")
			(options
				(clearance outline)
				(anchor circle)
			)
			(primitives
				(gr_poly
					(pts
						(arc
							(start -0.1778 -0.2794)
							(mid -0.249642 -0.249642)
							(end -0.2794 -0.1778)
						)
						(arc
							(start -0.2794 0.1778)
							(mid -0.249642 0.249642)
							(end -0.1778 0.2794)
						)
						(arc
							(start 0.1778 0.2794)
							(mid 0.249642 0.249642)
							(end 0.2794 0.1778)
						)
						(arc
							(start 0.2794 -0.1778)
							(mid 0.249642 -0.249642)
							(end 0.1778 -0.2794)
						)
					)
					(width 0)
					(fill yes)
				)
			)
		)
		(pad "2" smd custom
			(at 0 0.4445)
			(size 0.1397 0.1397)
			(layers "F.Cu" "F.Mask" "F.Paste")
			(net "SYS_DBMODE0")
			(options
				(clearance outline)
				(anchor circle)
			)
			(primitives
				(gr_poly
					(pts
						(arc
							(start -0.1778 -0.2794)
							(mid -0.249642 -0.249642)
							(end -0.2794 -0.1778)
						)
						(arc
							(start -0.2794 0.1778)
							(mid -0.249642 0.249642)
							(end -0.1778 0.2794)
						)
						(arc
							(start 0.1778 0.2794)
							(mid 0.249642 0.249642)
							(end 0.2794 0.1778)
						)
						(arc
							(start 0.2794 -0.1778)
							(mid 0.249642 -0.249642)
							(end 0.1778 -0.2794)
						)
					)
					(width 0)
					(fill yes)
				)
			)
		)
	)
	(footprint ""
		(layer "F.Cu")
		(at 173.1518 -39.5224)
		(property "Reference" "TP170"
			(at 0 0 0)
			(layer "F.SilkS")
			(hide yes)
			(effects
				(font
					(size 1.27 1.27)
				)
			)
		)
		(property "Value" "TPAD28-2-GP"
			(at -0.0127 -1.6637 0)
			(unlocked yes)
			(layer "F.Fab")
			(hide yes)
			(effects
				(font
					(size 1.016 1.016)
					(thickness 0.1524)
				)
			)
		)
		(property "Device Type" "TPAD28"
			(at -0.0127 -3.1877 0)
			(unlocked yes)
			(layer "F.Fab")
			(hide yes)
			(effects
				(font
					(size 1.016 1.016)
					(thickness 0.1524)
				)
			)
		)
		(duplicate_pad_numbers_are_jumpers no)
		(fp_poly
			(pts
				(arc
					(start 0.3556 0)
					(mid -0.3556 0)
					(end 0.3556 0)
				)
			)
			(stroke
				(width 0)
				(type default)
			)
			(fill no)
			(layer "F.CrtYd")
		)
		(fp_poly
			(pts
				(arc
					(start 0.6096 0)
					(mid -0.6096 0)
					(end 0.6096 0)
				)
			)
			(stroke
				(width 0)
				(type default)
			)
			(fill no)
			(layer "F.Fab")
		)
		(pad "1" smd circle
			(at 0 0)
			(size 0.7112 0.7112)
			(layers "F.Cu" "F.Mask" "F.Paste")
			(net "ZDEF_EXTA_TP_A1")
		)
	)
	(footprint ""
		(layer "F.Cu")
		(at 81.162144 -168.225216 180)
		(property "Reference" "C243"
			(at 0 0 180)
			(layer "F.SilkS")
			(hide yes)
			(effects
				(font
					(size 1.27 1.27)
				)
			)
		)
		(property "Value" "SC10U6D3V5KX-4GP"
			(at -0.0762 -6.1214 180)
			(unlocked yes)
			(layer "F.Fab")
			(hide yes)
			(effects
				(font
					(size 1.016 1.016)
					(thickness 0.1524)
				)
			)
		)
		(property "Device Type" "C805H58"
			(at -0.0762 -8.1534 180)
			(unlocked yes)
			(layer "F.Fab")
			(hide yes)
			(effects
				(font
					(size 1.016 1.016)
					(thickness 0.1524)
				)
			)
		)
		(duplicate_pad_numbers_are_jumpers no)
		(fp_line
			(start 0.635 0)
			(end -0.635 0)
			(stroke
				(width 0.508)
				(type default)
			)
			(layer "F.SilkS")
		)
		(fp_rect
			(start -0.9652 1.778)
			(end 0.9652 -1.778)
			(stroke
				(width 0)
				(type default)
			)
			(fill no)
			(layer "F.CrtYd")
		)
		(fp_poly
			(pts
				(xy -0.9652 -1.778) (xy 0.9652 -1.778) (xy 0.9652 1.778) (xy -0.9652 1.778)
			)
			(stroke
				(width 0)
				(type default)
			)
			(fill no)
			(layer "F.Fab")
		)
		(pad "1" smd rect
			(at 0 -0.9652 180)
			(size 1.397 1.143)
			(layers "F.Cu" "F.Mask" "F.Paste")
			(net "P1V8_STBY")
		)
		(pad "2" smd rect
			(at 0 0.9652 180)
			(size 1.397 1.143)
			(layers "F.Cu" "F.Mask" "F.Paste")
			(net "GND")
		)
	)
	(footprint ""
		(layer "F.Cu")
		(at 177.546 -73.6854)
		(property "Reference" "TP93"
			(at 0 0 0)
			(layer "F.SilkS")
			(hide yes)
			(effects
				(font
					(size 1.27 1.27)
				)
			)
		)
		(property "Value" "TPAD28-2-GP"
			(at -0.0127 -1.6637 0)
			(unlocked yes)
			(layer "F.Fab")
			(hide yes)
			(effects
				(font
					(size 1.016 1.016)
					(thickness 0.1524)
				)
			)
		)
		(property "Device Type" "TPAD28"
			(at -0.0127 -3.1877 0)
			(unlocked yes)
			(layer "F.Fab")
			(hide yes)
			(effects
				(font
					(size 1.016 1.016)
					(thickness 0.1524)
				)
			)
		)
		(duplicate_pad_numbers_are_jumpers no)
		(fp_poly
			(pts
				(arc
					(start 0.3556 0)
					(mid -0.3556 0)
					(end 0.3556 0)
				)
			)
			(stroke
				(width 0)
				(type default)
			)
			(fill no)
			(layer "F.CrtYd")
		)
		(fp_poly
			(pts
				(arc
					(start 0.6096 0)
					(mid -0.6096 0)
					(end 0.6096 0)
				)
			)
			(stroke
				(width 0)
				(type default)
			)
			(fill no)
			(layer "F.Fab")
		)
		(pad "1" smd circle
			(at 0 0)
			(size 0.7112 0.7112)
			(layers "F.Cu" "F.Mask" "F.Paste")
			(net "IOC_GPIO_8")
		)
	)
)
